FILE_TYPE = MULTI_PHYS_TABLE;

PART 'CONN60_101062636003K02LF'

{========================================================================================}
:VALUE                       | PART_TYPE | MATERIAL | PART_NUMBER    = STANDARD        | LIFECYCLE          | PART_NUMBER   | JEDEC_TYPE                      | DESCRIPTION                               | MANUFTR | MANUF_PN             | RD_CMPLS_LVL | CMPLS_LVL | CLASS | DIP_SMD | FROM_PJ    | DATA                         | FP_ECN                   | EE_CHECK_LIST | CREATOR | CREATEDAY  | PSL | STATUS | ESD_CDM | ESD_HBM | ESD_MM | MSD | PIN_LENGTH_LONG_PIN | PIN_LENGTH_SHORT_PIN ;
{========================================================================================}
 'CONN60_10106263-6003K02LF' | 'THLF'    | 'IO'     | 'DFHD60MR024'(!) = ''               | ''               | 'DFHD60MR024' |'HSD_M60D4H2D_P2-54W2-54_LDHXB'| 'CONN DIP HEADER 60P 4R MR(P2.54,H12.57)' | 'APL'   | '10106263-6003K02LF' | 'EP(V1)'     | ''        | 'IO'  | 'DIP'   | 'F0T-IVES' | 'APL_10106263-6003K02LF.pdf' | '10106263-6003K02LF.msg' | ''            | ''      | '20220513' | ''  | ''     | ''      | ''      | ''     | ''  | '136 MILS'          | '136 MILS'          
 'CONN60_10106263-6003K02LF' | 'THLF'    | 'EMPTY'  | 'DFHD60MR024'(!) = ''               | ''               | 'DFHD60MR024' |'HSD_M60D4H2D_P2-54W2-54_LDHXB'| 'CONN DIP HEADER 60P 4R MR(P2.54,H12.57)' | 'APL'   | '10106263-6003K02LF' | 'EP(V1)'     | ''        | 'IO'  | 'DIP'   | 'F0T-IVES' | 'APL_10106263-6003K02LF.pdf' | '10106263-6003K02LF.msg' | ''            | ''      | '20220513' | ''  | ''     | ''      | ''      | ''     | ''  | '136 MILS'          | '136 MILS'          

END_PART

END.

